# T6G (Grand Teton) — schematic netlist excerpt (pin names and nets, part order shuffled) for the footprints in the layout excerpt that follows; sources: Cadence DE-HDL packaged netlist, KiCad conversion of 04192023_DAF0TMB3IC0_F0TG_MB_C_brd_V02_OCP.brd

R834  Q_RES  1K 1% CHIP  pkg 0201LF  page 185 : A = P1V8_CPU0_RT_1D ; B = SMB_RT_CPU0_P0_ROM_R_SDA
R1075  Q_RES  4.7K 5% EMPTY  pkg 0201LF  page 298 : A = P1V8_CPU0_RT_1D ; B = TEST1_RT_CPU0_P2
C1174  Q_CAP  0.1UF 16V 10% X7R  pkg C0402  page 83 : A = P3V3_AUX ; B = GND
C977  Q_CAP  4.7UF 6.3V 20% X6S  pkg 0402  page 301 : A = P0V9_CPU0_RT2_2A ; B = GND

(kicad_pcb
	(version 20260206)
	(generator "pcbnew")
	(generator_version "10.0")
	(general
		(thickness 1.6)
		(legacy_teardrops no)
	)
	(paper "A4")
	(title_block
		(title "04192023_DAF0TMB3IC0_F0TG_MB_C_brd_V02_OCP.brd")
		(comment 1 "Grand Teton / footprints 5229-5232 of 8354")
	)
	(layers
		(0 "F.Cu" signal "TOP")
		(4 "In1.Cu" signal "GND")
		(6 "In2.Cu" signal "IN1")
		(8 "In3.Cu" signal "GND1")
		(10 "In4.Cu" signal "IN2")
		(12 "In5.Cu" signal "GND2")
		(14 "In6.Cu" signal "IN3")
		(16 "In7.Cu" signal "GND3")
		(18 "In8.Cu" signal "VCC")
		(20 "In9.Cu" signal "VCC1")
		(22 "In10.Cu" signal "GND4")
		(24 "In11.Cu" signal "IN4")
		(26 "In12.Cu" signal "GND5")
		(28 "In13.Cu" signal "IN5")
		(30 "In14.Cu" signal "GND6")
		(32 "In15.Cu" signal "IN6")
		(34 "In16.Cu" signal "GND7")
		(2 "B.Cu" signal "BOTTOM")
		(9 "F.Adhes" user "F.Adhesive")
		(11 "B.Adhes" user "B.Adhesive")
		(13 "F.Paste" user "Package Geometry/Pastemask Top")
		(15 "B.Paste" user "Package Geometry/Pastemask Bottom")
		(5 "F.SilkS" user "Ref Des/Silkscreen Top")
		(7 "B.SilkS" user "Ref Des/Silkscreen Bottom")
		(1 "F.Mask" user "Board Geometry/Soldermask Top")
		(3 "B.Mask" user "Board Geometry/Soldermask Bottom")
		(17 "Dwgs.User" user "User.Drawings")
		(19 "Cmts.User" user "User.Comments")
		(21 "Eco1.User" user "User.Eco1")
		(23 "Eco2.User" user "User.Eco2")
		(25 "Edge.Cuts" user "Board Geometry/Outline")
		(27 "Margin" user)
		(31 "F.CrtYd" user "Package Geometry/Place Bound Top")
		(29 "B.CrtYd" user "Package Geometry/Place Bound Bottom")
		(35 "F.Fab" user "Ref Des/Assembly Top")
		(33 "B.Fab" user "Ref Des/Assembly Bottom")
	)
	(footprint ""
		(layer "B.Cu")
		(at 419.819074 -398.942052 90)
		(property "Reference" "C977"
			(at 0 0 90)
			(layer "B.SilkS")
			(hide yes)
			(effects
				(font
					(size 1.27 1.27)
				)
				(justify mirror)
			)
		)
		(property "Value" ""
			(at 0 0 90)
			(layer "B.Fab")
			(effects
				(font
					(size 1.27 1.27)
				)
				(justify mirror)
			)
		)
		(duplicate_pad_numbers_are_jumpers no)
		(fp_line
			(start 0.7874 -0.4064)
			(end -0.7874 -0.4064)
			(stroke
				(width 0.1524)
				(type default)
			)
			(layer "B.SilkS")
		)
		(fp_line
			(start -0.7874 -0.4064)
			(end -0.7874 0.4064)
			(stroke
				(width 0.1524)
				(type default)
			)
			(layer "B.SilkS")
		)
		(fp_line
			(start 0.7874 0.4064)
			(end 0.7874 -0.4064)
			(stroke
				(width 0.1524)
				(type default)
			)
			(layer "B.SilkS")
		)
		(fp_line
			(start -0.7874 0.4064)
			(end 0.7874 0.4064)
			(stroke
				(width 0.1524)
				(type default)
			)
			(layer "B.SilkS")
		)
		(fp_line
			(start 0.67945 -0.305054)
			(end 0.12065 -0.305054)
			(stroke
				(width 0.1)
				(type default)
			)
			(layer "B.Fab")
		)
		(fp_line
			(start 0.12065 -0.305054)
			(end 0.12065 -0.2794)
			(stroke
				(width 0.1)
				(type default)
			)
			(layer "B.Fab")
		)
		(fp_line
			(start -0.12065 -0.3048)
			(end -0.67945 -0.3048)
			(stroke
				(width 0.1)
				(type default)
			)
			(layer "B.Fab")
		)
		(fp_line
			(start -0.67945 -0.3048)
			(end -0.67945 0.3048)
			(stroke
				(width 0.1)
				(type default)
			)
			(layer "B.Fab")
		)
		(fp_line
			(start 0.12065 -0.2794)
			(end -0.12065 -0.2794)
			(stroke
				(width 0.1)
				(type default)
			)
			(layer "B.Fab")
		)
		(fp_line
			(start -0.12065 -0.2794)
			(end -0.12065 -0.3048)
			(stroke
				(width 0.1)
				(type default)
			)
			(layer "B.Fab")
		)
		(fp_line
			(start 0.12065 0.2794)
			(end 0.12065 0.3048)
			(stroke
				(width 0.1)
				(type default)
			)
			(layer "B.Fab")
		)
		(fp_line
			(start -0.120396 0.2794)
			(end 0.12065 0.2794)
			(stroke
				(width 0.1)
				(type default)
			)
			(layer "B.Fab")
		)
		(fp_line
			(start 0.67945 0.3048)
			(end 0.67945 -0.305054)
			(stroke
				(width 0.1)
				(type default)
			)
			(layer "B.Fab")
		)
		(fp_line
			(start 0.12065 0.3048)
			(end 0.67945 0.3048)
			(stroke
				(width 0.1)
				(type default)
			)
			(layer "B.Fab")
		)
		(fp_line
			(start -0.120396 0.3048)
			(end -0.120396 0.2794)
			(stroke
				(width 0.1)
				(type default)
			)
			(layer "B.Fab")
		)
		(fp_line
			(start -0.67945 0.3048)
			(end -0.120396 0.3048)
			(stroke
				(width 0.1)
				(type default)
			)
			(layer "B.Fab")
		)
		(pad "1" smd circle
			(at 0.40005 0 270)
			(size 0 0)
			(layers "B.Cu" "B.Mask" "B.Paste")
			(net "P0V9_CPU0_RT2_2A")
		)
		(pad "2" smd circle
			(at -0.40005 0 270)
			(size 0 0)
			(layers "B.Cu" "B.Mask" "B.Paste")
			(net "GND")
		)
	)
	(footprint ""
		(layer "B.Cu")
		(at 397.623538 -393.04468 180)
		(property "Reference" "R1075"
			(at 0 0 0)
			(layer "B.SilkS")
			(hide yes)
			(effects
				(font
					(size 1.27 1.27)
				)
				(justify mirror)
			)
		)
		(property "Value" ""
			(at 0 0 0)
			(layer "B.Fab")
			(effects
				(font
					(size 1.27 1.27)
				)
				(justify mirror)
			)
		)
		(duplicate_pad_numbers_are_jumpers no)
		(fp_line
			(start 0.32512 0.175006)
			(end 0.32512 -0.175006)
			(stroke
				(width 0.1)
				(type default)
			)
			(layer "B.Fab")
		)
		(fp_line
			(start 0.32512 -0.175006)
			(end -0.32512 -0.175006)
			(stroke
				(width 0.1)
				(type default)
			)
			(layer "B.Fab")
		)
		(fp_line
			(start -0.32512 0.175006)
			(end 0.32512 0.175006)
			(stroke
				(width 0.1)
				(type default)
			)
			(layer "B.Fab")
		)
		(fp_line
			(start -0.32512 -0.175006)
			(end -0.32512 0.175006)
			(stroke
				(width 0.1)
				(type default)
			)
			(layer "B.Fab")
		)
		(pad "1" smd rect
			(at 0.2667 0)
			(size 0.3048 0.381)
			(layers "B.Cu" "B.Mask" "B.Paste")
			(net "P1V8_CPU0_RT_1D")
		)
		(pad "2" smd rect
			(at -0.2667 0 180)
			(size 0.3048 0.381)
			(layers "B.Cu" "B.Mask" "B.Paste")
			(net "TEST1_RT_CPU0_P2")
		)
	)
	(footprint ""
		(layer "B.Cu")
		(at 295.402 -424.942 180)
		(property "Reference" "R834"
			(at 0 0 0)
			(layer "B.SilkS")
			(hide yes)
			(effects
				(font
					(size 1.27 1.27)
				)
				(justify mirror)
			)
		)
		(property "Value" ""
			(at 0 0 0)
			(layer "B.Fab")
			(effects
				(font
					(size 1.27 1.27)
				)
				(justify mirror)
			)
		)
		(duplicate_pad_numbers_are_jumpers no)
		(fp_line
			(start 0.32512 0.175006)
			(end 0.32512 -0.175006)
			(stroke
				(width 0.1)
				(type default)
			)
			(layer "B.Fab")
		)
		(fp_line
			(start 0.32512 -0.175006)
			(end -0.32512 -0.175006)
			(stroke
				(width 0.1)
				(type default)
			)
			(layer "B.Fab")
		)
		(fp_line
			(start -0.32512 0.175006)
			(end 0.32512 0.175006)
			(stroke
				(width 0.1)
				(type default)
			)
			(layer "B.Fab")
		)
		(fp_line
			(start -0.32512 -0.175006)
			(end -0.32512 0.175006)
			(stroke
				(width 0.1)
				(type default)
			)
			(layer "B.Fab")
		)
		(pad "1" smd rect
			(at 0.2667 0)
			(size 0.3048 0.381)
			(layers "B.Cu" "B.Mask" "B.Paste")
			(net "P1V8_CPU0_RT_1D")
		)
		(pad "2" smd rect
			(at -0.2667 0 180)
			(size 0.3048 0.381)
			(layers "B.Cu" "B.Mask" "B.Paste")
			(net "SMB_RT_CPU0_P0_ROM_R_SDA")
		)
	)
	(footprint ""
		(layer "B.Cu")
		(at 184.332372 -116.642896 -90)
		(property "Reference" "C1174"
			(at 0 0 90)
			(layer "B.SilkS")
			(hide yes)
			(effects
				(font
					(size 1.27 1.27)
				)
				(justify mirror)
			)
		)
		(property "Value" ""
			(at 0 0 90)
			(layer "B.Fab")
			(effects
				(font
					(size 1.27 1.27)
				)
				(justify mirror)
			)
		)
		(duplicate_pad_numbers_are_jumpers no)
		(fp_line
			(start -0.69215 0.2921)
			(end 0.69215 0.2921)
			(stroke
				(width 0.1524)
				(type default)
			)
			(layer "B.SilkS")
		)
		(fp_line
			(start 0.69215 0.2921)
			(end 0.69215 -0.2921)
			(stroke
				(width 0.1524)
				(type default)
			)
			(layer "B.SilkS")
		)
		(fp_line
			(start -0.69215 -0.2921)
			(end -0.69215 0.2921)
			(stroke
				(width 0.1524)
				(type default)
			)
			(layer "B.SilkS")
		)
		(fp_line
			(start 0.69215 -0.2921)
			(end -0.69215 -0.2921)
			(stroke
				(width 0.1524)
				(type default)
			)
			(layer "B.SilkS")
		)
		(fp_line
			(start -0.51435 0.2794)
			(end 0.51435 0.2794)
			(stroke
				(width 0.1)
				(type default)
			)
			(layer "B.Fab")
		)
		(fp_line
			(start 0.51435 0.2794)
			(end 0.51435 -0.2794)
			(stroke
				(width 0.1)
				(type default)
			)
			(layer "B.Fab")
		)
		(fp_line
			(start -0.51435 -0.2794)
			(end -0.51435 0.2794)
			(stroke
				(width 0.1)
				(type default)
			)
			(layer "B.Fab")
		)
		(fp_line
			(start 0.51435 -0.2794)
			(end -0.51435 -0.2794)
			(stroke
				(width 0.1)
				(type default)
			)
			(layer "B.Fab")
		)
		(pad "1" smd circle
			(at 0.40005 0 90)
			(size 0 0)
			(layers "B.Cu" "B.Mask" "B.Paste")
			(net "P3V3_AUX")
		)
		(pad "2" smd circle
			(at -0.40005 0 90)
			(size 0 0)
			(layers "B.Cu" "B.Mask" "B.Paste")
			(net "GND")
		)
		(zone
			(layer "B.Cu")
			(hatch none 0.5)
			(connect_pads
				(clearance 0)
			)
			(min_thickness 0.25)
			(keepout
				(tracks not_allowed)
				(vias allowed)
				(pads allowed)
				(copperpour not_allowed)
				(footprints allowed)
			)
			(placement
				(enabled no)
				(sheetname "")
			)
			(fill
				(thermal_gap 0.5)
				(thermal_bridge_width 0.5)
				(island_removal_mode 0)
			)
			(polygon
				(pts
					(xy 184.186576 -116.543836) (xy 184.186576 -116.743226) (xy 184.244742 -116.833396) (xy 184.420002 -116.833396)
					(xy 184.478422 -116.743226) (xy 184.478422 -116.543836) (xy 184.420256 -116.452396) (xy 184.244742 -116.452396)
				)
			)
		)
	)
)
